# T6G (Grand Teton) — schematic netlist excerpt (pin names and nets, part order shuffled) for the footprints in the layout excerpt that follows; sources: Cadence DE-HDL packaged netlist, KiCad conversion of 04192023_DAF0TMB3IC0_F0TG_MB_C_brd_V02_OCP.brd

R3645  Q_RES  0.002 1% CHIP  pkg 2512LF  page 236 : A = P3V3_OCP_SFF ; B = P3V3_OCP_SFF_R
PC612  Q_CAP  0.22UF 16V 10% X7R  pkg 0402  page 199 : A = SW_PVDDCR_SOC_P0_BOOT3_RC ; B = SW_PVDDCR_SOC_P0_PH3
C1869  Q_CAP  0.1UF 25V 10% X7R  pkg 0402  page 113 : A = P2E_MB_BMC_RX_BUF_C_DN<0> ; B = P2E_MB_BMC_RX_BUF_DN<0>

(kicad_pcb
	(version 20260206)
	(generator "pcbnew")
	(generator_version "10.0")
	(general
		(thickness 1.6)
		(legacy_teardrops no)
	)
	(paper "A4")
	(title_block
		(title "04192023_DAF0TMB3IC0_F0TG_MB_C_brd_V02_OCP.brd")
		(comment 1 "Grand Teton / footprints 2173-2175 of 8354")
	)
	(layers
		(0 "F.Cu" signal "TOP")
		(4 "In1.Cu" signal "GND")
		(6 "In2.Cu" signal "IN1")
		(8 "In3.Cu" signal "GND1")
		(10 "In4.Cu" signal "IN2")
		(12 "In5.Cu" signal "GND2")
		(14 "In6.Cu" signal "IN3")
		(16 "In7.Cu" signal "GND3")
		(18 "In8.Cu" signal "VCC")
		(20 "In9.Cu" signal "VCC1")
		(22 "In10.Cu" signal "GND4")
		(24 "In11.Cu" signal "IN4")
		(26 "In12.Cu" signal "GND5")
		(28 "In13.Cu" signal "IN5")
		(30 "In14.Cu" signal "GND6")
		(32 "In15.Cu" signal "IN6")
		(34 "In16.Cu" signal "GND7")
		(2 "B.Cu" signal "BOTTOM")
		(9 "F.Adhes" user "F.Adhesive")
		(11 "B.Adhes" user "B.Adhesive")
		(13 "F.Paste" user "Package Geometry/Pastemask Top")
		(15 "B.Paste" user "Package Geometry/Pastemask Bottom")
		(5 "F.SilkS" user "Ref Des/Silkscreen Top")
		(7 "B.SilkS" user "Ref Des/Silkscreen Bottom")
		(1 "F.Mask" user "Board Geometry/Soldermask Top")
		(3 "B.Mask" user "Board Geometry/Soldermask Bottom")
		(17 "Dwgs.User" user "User.Drawings")
		(19 "Cmts.User" user "User.Comments")
		(21 "Eco1.User" user "User.Eco1")
		(23 "Eco2.User" user "User.Eco2")
		(25 "Edge.Cuts" user "Board Geometry/Outline")
		(27 "Margin" user)
		(31 "F.CrtYd" user "Package Geometry/Place Bound Top")
		(29 "B.CrtYd" user "Package Geometry/Place Bound Bottom")
		(35 "F.Fab" user "Ref Des/Assembly Top")
		(33 "B.Fab" user "Ref Des/Assembly Bottom")
	)
	(footprint ""
		(layer "F.Cu")
		(at 39.15029 -425.256706)
		(property "Reference" "C1869"
			(at 0 0 0)
			(layer "F.SilkS")
			(hide yes)
			(effects
				(font
					(size 1.27 1.27)
				)
			)
		)
		(property "Value" ""
			(at 0 0 0)
			(layer "F.Fab")
			(effects
				(font
					(size 1.27 1.27)
				)
			)
		)
		(duplicate_pad_numbers_are_jumpers no)
		(fp_line
			(start -0.7874 -0.4064)
			(end -0.33909 -0.4064)
			(stroke
				(width 0.1524)
				(type default)
			)
			(layer "F.SilkS")
		)
		(fp_line
			(start 0.7874 -0.294894)
			(end 0.7874 0.4064)
			(stroke
				(width 0.1524)
				(type default)
			)
			(layer "F.SilkS")
		)
		(fp_line
			(start 0.7874 0.4064)
			(end -0.7874 0.4064)
			(stroke
				(width 0.1524)
				(type default)
			)
			(layer "F.SilkS")
		)
		(fp_line
			(start -0.6858 -0.3048)
			(end -0.1016 -0.3048)
			(stroke
				(width 0.1)
				(type default)
			)
			(layer "F.Fab")
		)
		(fp_line
			(start -0.6858 0.3048)
			(end -0.6858 -0.3048)
			(stroke
				(width 0.1)
				(type default)
			)
			(layer "F.Fab")
		)
		(fp_line
			(start -0.1016 -0.3048)
			(end -0.1016 -0.2794)
			(stroke
				(width 0.1)
				(type default)
			)
			(layer "F.Fab")
		)
		(fp_line
			(start -0.1016 -0.2794)
			(end 0.1016 -0.2794)
			(stroke
				(width 0.1)
				(type default)
			)
			(layer "F.Fab")
		)
		(fp_line
			(start -0.1016 0.2794)
			(end -0.1016 0.3048)
			(stroke
				(width 0.1)
				(type default)
			)
			(layer "F.Fab")
		)
		(fp_line
			(start -0.1016 0.3048)
			(end -0.6858 0.3048)
			(stroke
				(width 0.1)
				(type default)
			)
			(layer "F.Fab")
		)
		(fp_line
			(start 0.1016 -0.3048)
			(end 0.6858 -0.3048)
			(stroke
				(width 0.1)
				(type default)
			)
			(layer "F.Fab")
		)
		(fp_line
			(start 0.1016 -0.2794)
			(end 0.1016 -0.3048)
			(stroke
				(width 0.1)
				(type default)
			)
			(layer "F.Fab")
		)
		(fp_line
			(start 0.1016 0.2794)
			(end -0.1016 0.2794)
			(stroke
				(width 0.1)
				(type default)
			)
			(layer "F.Fab")
		)
		(fp_line
			(start 0.1016 0.3048)
			(end 0.1016 0.2794)
			(stroke
				(width 0.1)
				(type default)
			)
			(layer "F.Fab")
		)
		(fp_line
			(start 0.6858 -0.3048)
			(end 0.6858 0.3048)
			(stroke
				(width 0.1)
				(type default)
			)
			(layer "F.Fab")
		)
		(fp_line
			(start 0.6858 0.3048)
			(end 0.1016 0.3048)
			(stroke
				(width 0.1)
				(type default)
			)
			(layer "F.Fab")
		)
		(pad "1" smd rect
			(at -0.40005 0 180)
			(size 0.4572 0.508)
			(layers "F.Cu" "F.Mask" "F.Paste")
			(net "P2E_MB_BMC_RX_BUF_C_DN<0>")
		)
		(pad "2" smd rect
			(at 0.40005 0 180)
			(size 0.4572 0.508)
			(layers "F.Cu" "F.Mask" "F.Paste")
			(net "P2E_MB_BMC_RX_BUF_DN<0>")
		)
	)
	(footprint ""
		(layer "F.Cu")
		(at 430.827434 -98.175064 180)
		(property "Reference" "R3645"
			(at 2.202434 2.636266 0)
			(unlocked yes)
			(layer "F.SilkS")
			(effects
				(font
					(size 0.7874 0.5842)
					(thickness 0.1524)
				)
				(justify left)
			)
		)
		(property "Value" ""
			(at 0 0 180)
			(layer "F.Fab")
			(effects
				(font
					(size 1.27 1.27)
				)
			)
		)
		(duplicate_pad_numbers_are_jumpers no)
		(fp_line
			(start 3.937508 1.8796)
			(end 3.937508 -1.8796)
			(stroke
				(width 0.1524)
				(type default)
			)
			(layer "F.SilkS")
		)
		(fp_line
			(start 3.937508 -1.8796)
			(end -3.937508 -1.8796)
			(stroke
				(width 0.1524)
				(type default)
			)
			(layer "F.SilkS")
		)
		(fp_line
			(start -3.937508 1.8796)
			(end 3.937508 1.8796)
			(stroke
				(width 0.1524)
				(type default)
			)
			(layer "F.SilkS")
		)
		(fp_line
			(start -3.937508 -1.8796)
			(end -3.937508 1.8796)
			(stroke
				(width 0.1524)
				(type default)
			)
			(layer "F.SilkS")
		)
		(fp_line
			(start 3.275076 1.674876)
			(end 3.275076 -1.674876)
			(stroke
				(width 0.1)
				(type default)
			)
			(layer "F.Fab")
		)
		(fp_line
			(start 3.275076 -1.674876)
			(end -3.275076 -1.674876)
			(stroke
				(width 0.1)
				(type default)
			)
			(layer "F.Fab")
		)
		(fp_line
			(start -3.275076 1.674876)
			(end 3.275076 1.674876)
			(stroke
				(width 0.1)
				(type default)
			)
			(layer "F.Fab")
		)
		(fp_line
			(start -3.275076 -1.674876)
			(end -3.275076 1.674876)
			(stroke
				(width 0.1)
				(type default)
			)
			(layer "F.Fab")
		)
		(pad "1" smd rect
			(at -2.350008 0 180)
			(size 2.921 3.5052)
			(layers "F.Cu" "F.Mask" "F.Paste")
			(net "P3V3_OCP_SFF")
		)
		(pad "2" smd rect
			(at 2.350008 0 180)
			(size 2.921 3.5052)
			(layers "F.Cu" "F.Mask" "F.Paste")
			(net "P3V3_OCP_SFF_R")
		)
	)
	(footprint ""
		(layer "F.Cu")
		(at 412.743904 -159.116014 90)
		(property "Reference" "PC612"
			(at 0 0 90)
			(layer "F.SilkS")
			(hide yes)
			(effects
				(font
					(size 1.27 1.27)
				)
			)
		)
		(property "Value" ""
			(at 0 0 90)
			(layer "F.Fab")
			(effects
				(font
					(size 1.27 1.27)
				)
			)
		)
		(duplicate_pad_numbers_are_jumpers no)
		(fp_line
			(start 0.7874 -0.4064)
			(end 0.7874 0.4064)
			(stroke
				(width 0.1524)
				(type default)
			)
			(layer "F.SilkS")
		)
		(fp_line
			(start -0.7874 -0.4064)
			(end 0.7874 -0.4064)
			(stroke
				(width 0.1524)
				(type default)
			)
			(layer "F.SilkS")
		)
		(fp_line
			(start 0.7874 0.4064)
			(end -0.7874 0.4064)
			(stroke
				(width 0.1524)
				(type default)
			)
			(layer "F.SilkS")
		)
		(fp_line
			(start -0.7874 0.4064)
			(end -0.7874 -0.4064)
			(stroke
				(width 0.1524)
				(type default)
			)
			(layer "F.SilkS")
		)
		(fp_line
			(start -0.12065 -0.305054)
			(end -0.12065 -0.2794)
			(stroke
				(width 0.1)
				(type default)
			)
			(layer "F.Fab")
		)
		(fp_line
			(start -0.67945 -0.305054)
			(end -0.12065 -0.305054)
			(stroke
				(width 0.1)
				(type default)
			)
			(layer "F.Fab")
		)
		(fp_line
			(start 0.67945 -0.3048)
			(end 0.67945 0.3048)
			(stroke
				(width 0.1)
				(type default)
			)
			(layer "F.Fab")
		)
		(fp_line
			(start 0.12065 -0.3048)
			(end 0.67945 -0.3048)
			(stroke
				(width 0.1)
				(type default)
			)
			(layer "F.Fab")
		)
		(fp_line
			(start 0.12065 -0.2794)
			(end 0.12065 -0.3048)
			(stroke
				(width 0.1)
				(type default)
			)
			(layer "F.Fab")
		)
		(fp_line
			(start -0.12065 -0.2794)
			(end 0.12065 -0.2794)
			(stroke
				(width 0.1)
				(type default)
			)
			(layer "F.Fab")
		)
		(fp_line
			(start 0.120396 0.2794)
			(end -0.12065 0.2794)
			(stroke
				(width 0.1)
				(type default)
			)
			(layer "F.Fab")
		)
		(fp_line
			(start -0.12065 0.2794)
			(end -0.12065 0.3048)
			(stroke
				(width 0.1)
				(type default)
			)
			(layer "F.Fab")
		)
		(fp_line
			(start 0.67945 0.3048)
			(end 0.120396 0.3048)
			(stroke
				(width 0.1)
				(type default)
			)
			(layer "F.Fab")
		)
		(fp_line
			(start 0.120396 0.3048)
			(end 0.120396 0.2794)
			(stroke
				(width 0.1)
				(type default)
			)
			(layer "F.Fab")
		)
		(fp_line
			(start -0.12065 0.3048)
			(end -0.67945 0.3048)
			(stroke
				(width 0.1)
				(type default)
			)
			(layer "F.Fab")
		)
		(fp_line
			(start -0.67945 0.3048)
			(end -0.67945 -0.305054)
			(stroke
				(width 0.1)
				(type default)
			)
			(layer "F.Fab")
		)
		(pad "1" smd circle
			(at -0.40005 0 90)
			(size 0 0)
			(layers "F.Cu" "F.Mask" "F.Paste")
			(net "SW_PVDDCR_SOC_P0_BOOT3_RC")
		)
		(pad "2" smd circle
			(at 0.40005 0 90)
			(size 0 0)
			(layers "F.Cu" "F.Mask" "F.Paste")
			(net "SW_PVDDCR_SOC_P0_PH3")
		)
	)
)
